(kicad_pcb
	(version 20241229)
	(generator "pcbnew")
	(generator_version "9.0")
	(general
		(thickness 1.599998)
		(legacy_teardrops no)
	)
	(paper "A4")
	(title_block
		(title "Artix - Datacenter Secure Control Module (DC-SCM)")
		(date "2024-11-06")
		(rev "1.1.3")
		(comment 9 "footprints 164-168 of 544")
	)
	(layers
		(0 "F.Cu" signal)
		(4 "In1.Cu" signal)
		(6 "In2.Cu" signal)
		(8 "In3.Cu" signal)
		(10 "In4.Cu" signal)
		(12 "In5.Cu" signal)
		(14 "In6.Cu" signal)
		(2 "B.Cu" signal)
		(9 "F.Adhes" user "F.Adhesive")
		(11 "B.Adhes" user "B.Adhesive")
		(13 "F.Paste" user)
		(15 "B.Paste" user)
		(5 "F.SilkS" user "F.Silkscreen")
		(7 "B.SilkS" user "B.Silkscreen")
		(1 "F.Mask" user)
		(3 "B.Mask" user)
		(17 "Dwgs.User" user "User.Drawings")
		(19 "Cmts.User" user "User.Comments")
		(21 "Eco1.User" user "User.Eco1")
		(23 "Eco2.User" user "User.Eco2")
		(25 "Edge.Cuts" user)
		(27 "Margin" user)
		(31 "F.CrtYd" user "F.Courtyard")
		(29 "B.CrtYd" user "B.Courtyard")
		(35 "F.Fab" user)
		(33 "B.Fab" user)
	)
	(footprint "antmicro-footprints:C_0402_1005Metric"
		(layer "F.Cu")
		(at 91.52 74.4 90)
		(descr "Capacitor SMD 0402")
		(tags "capacitor SMD 0402")
		(property "Reference" "C3"
			(at -1 3.58 90)
			(layer "F.SilkS")
			(effects
				(font
					(size 0.7 0.7)
					(thickness 0.15)
				)
				(justify left bottom)
			)
		)
		(property "Value" "C_120p_0402"
			(at 0 1.4 90)
			(layer "F.Fab")
			(effects
				(font
					(size 0.7 0.7)
					(thickness 0.15)
				)
				(justify left bottom)
			)
		)
		(property "Datasheet" "https://www.kemet.com/en/us/capacitors/product/C0402C121J5GACTU.html"
			(at 0 0 90)
			(layer "F.Fab")
			(hide yes)
			(effects
				(font
					(size 1.27 1.27)
					(thickness 0.15)
				)
			)
		)
		(property "Description" "120 pF ±2% 100V Ceramic Capacitor C0G, NP0 0402 (1005 Metric)"
			(at 0 0 90)
			(layer "F.Fab")
			(hide yes)
			(effects
				(font
					(size 1.27 1.27)
					(thickness 0.15)
				)
			)
		)
		(property "Author" "Antmicro"
			(at 165.92 -17.12 0)
			(layer "F.Fab")
			(hide yes)
			(effects
				(font
					(size 1 1)
					(thickness 0.15)
				)
			)
		)
		(property "Dielectric" "C0G"
			(at 165.92 -17.12 0)
			(layer "F.Fab")
			(hide yes)
			(effects
				(font
					(size 1 1)
					(thickness 0.15)
				)
			)
		)
		(property "License" "Apache-2.0"
			(at 165.92 -17.12 0)
			(layer "F.Fab")
			(hide yes)
			(effects
				(font
					(size 1 1)
					(thickness 0.15)
				)
			)
		)
		(property "MPN" "C0402C121J5GACTU"
			(at 165.92 -17.12 0)
			(layer "F.Fab")
			(hide yes)
			(effects
				(font
					(size 1 1)
					(thickness 0.15)
				)
			)
		)
		(property "Manufacturer" "KEMET"
			(at 165.92 -17.12 0)
			(layer "F.Fab")
			(hide yes)
			(effects
				(font
					(size 1 1)
					(thickness 0.15)
				)
			)
		)
		(property "Val" "120p"
			(at 165.92 -17.12 0)
			(layer "F.Fab")
			(hide yes)
			(effects
				(font
					(size 1 1)
					(thickness 0.15)
				)
			)
		)
		(property "Voltage" "100V"
			(at 165.92 -17.12 0)
			(layer "F.Fab")
			(hide yes)
			(effects
				(font
					(size 1 1)
					(thickness 0.15)
				)
			)
		)
		(sheetname "/Power supply/")
		(sheetfile "power-supply.kicad_sch")
		(attr smd)
		(fp_rect
			(start -0.925 -0.47)
			(end 0.925 0.47)
			(stroke
				(width 0.05)
				(type default)
			)
			(fill no)
			(layer "F.CrtYd")
		)
		(fp_line
			(start 0.504 -0.25)
			(end 0.504 0.248)
			(stroke
				(width 0.15)
				(type solid)
			)
			(layer "F.Fab")
		)
		(fp_line
			(start -0.494 -0.25)
			(end 0.504 -0.25)
			(stroke
				(width 0.15)
				(type solid)
			)
			(layer "F.Fab")
		)
		(fp_line
			(start 0.504 0.248)
			(end -0.494 0.248)
			(stroke
				(width 0.15)
				(type solid)
			)
			(layer "F.Fab")
		)
		(fp_line
			(start -0.494 0.248)
			(end -0.494 -0.25)
			(stroke
				(width 0.15)
				(type solid)
			)
			(layer "F.Fab")
		)
		(pad "1" smd roundrect
			(at -0.48 0 90)
			(size 0.59 0.64)
			(layers "F.Cu" "F.Mask" "F.Paste")
			(roundrect_rratio 0.25)
			(net 10 "Net-(U16-FB)")
			(pintype "passive")
		)
		(pad "2" smd roundrect
			(at 0.48 0 90)
			(size 0.59 0.64)
			(layers "F.Cu" "F.Mask" "F.Paste")
			(roundrect_rratio 0.25)
			(net 60 "Net-(C101-Pad2)")
			(pintype "passive")
		)
	)
	(footprint "antmicro-footprints:C_0402_1005Metric"
		(layer "F.Cu")
		(at 85.87 72 180)
		(descr "Capacitor SMD 0402")
		(tags "capacitor SMD 0402")
		(property "Reference" "C101"
			(at -3.63 -0.4 0)
			(layer "F.SilkS")
			(effects
				(font
					(size 0.7 0.7)
					(thickness 0.15)
				)
				(justify right bottom)
			)
		)
		(property "Value" "C_10u_0402"
			(at 0 1.4 0)
			(layer "F.Fab")
			(effects
				(font
					(size 0.7 0.7)
					(thickness 0.15)
				)
				(justify right bottom)
			)
		)
		(property "Datasheet" "https://www.yageo.com/en/Chart/Download/pdf/CC0402MRX5R5BB106"
			(at 0 0 180)
			(layer "F.Fab")
			(hide yes)
			(effects
				(font
					(size 1.27 1.27)
					(thickness 0.15)
				)
			)
		)
		(property "Description" "SMD Multilayer Ceramic Capacitor, 10 µF, 6.3 V, 0402 [1005 Metric], ± 20%, X5R, CC Series"
			(at 0 0 180)
			(layer "F.Fab")
			(hide yes)
			(effects
				(font
					(size 1.27 1.27)
					(thickness 0.15)
				)
			)
		)
		(property "Author" "Antmicro"
			(at 171.74 144 0)
			(layer "F.Fab")
			(hide yes)
			(effects
				(font
					(size 1 1)
					(thickness 0.15)
				)
			)
		)
		(property "Dielectric" ""
			(at 171.74 144 0)
			(layer "F.Fab")
			(hide yes)
			(effects
				(font
					(size 1 1)
					(thickness 0.15)
				)
			)
		)
		(property "License" "Apache-2.0"
			(at 171.74 144 0)
			(layer "F.Fab")
			(hide yes)
			(effects
				(font
					(size 1 1)
					(thickness 0.15)
				)
			)
		)
		(property "MPN" "CC0402MRX5R5BB106"
			(at 171.74 144 0)
			(layer "F.Fab")
			(hide yes)
			(effects
				(font
					(size 1 1)
					(thickness 0.15)
				)
			)
		)
		(property "Manufacturer" "YAGEO"
			(at 171.74 144 0)
			(layer "F.Fab")
			(hide yes)
			(effects
				(font
					(size 1 1)
					(thickness 0.15)
				)
			)
		)
		(property "Val" "10u"
			(at 171.74 144 0)
			(layer "F.Fab")
			(hide yes)
			(effects
				(font
					(size 1 1)
					(thickness 0.15)
				)
			)
		)
		(property "Voltage" ""
			(at 171.74 144 0)
			(layer "F.Fab")
			(hide yes)
			(effects
				(font
					(size 1 1)
					(thickness 0.15)
				)
			)
		)
		(sheetname "/Power supply/")
		(sheetfile "power-supply.kicad_sch")
		(attr smd)
		(fp_rect
			(start -0.925 -0.47)
			(end 0.925 0.47)
			(stroke
				(width 0.05)
				(type default)
			)
			(fill no)
			(layer "F.CrtYd")
		)
		(fp_line
			(start 0.504 0.248)
			(end -0.494 0.248)
			(stroke
				(width 0.15)
				(type solid)
			)
			(layer "F.Fab")
		)
		(fp_line
			(start 0.504 -0.25)
			(end 0.504 0.248)
			(stroke
				(width 0.15)
				(type solid)
			)
			(layer "F.Fab")
		)
		(fp_line
			(start -0.494 0.248)
			(end -0.494 -0.25)
			(stroke
				(width 0.15)
				(type solid)
			)
			(layer "F.Fab")
		)
		(fp_line
			(start -0.494 -0.25)
			(end 0.504 -0.25)
			(stroke
				(width 0.15)
				(type solid)
			)
			(layer "F.Fab")
		)
		(pad "1" smd roundrect
			(at -0.48 0 180)
			(size 0.59 0.64)
			(layers "F.Cu" "F.Mask" "F.Paste")
			(roundrect_rratio 0.25)
			(net 1 "GND")
			(pintype "passive")
		)
		(pad "2" smd roundrect
			(at 0.48 0 180)
			(size 0.59 0.64)
			(layers "F.Cu" "F.Mask" "F.Paste")
			(roundrect_rratio 0.25)
			(net 60 "Net-(C101-Pad2)")
			(pintype "passive")
		)
	)
	(footprint "antmicro-footprints:C_0402_1005Metric"
		(layer "F.Cu")
		(at 85.875 70.665 180)
		(descr "Capacitor SMD 0402")
		(tags "capacitor SMD 0402")
		(property "Reference" "C103"
			(at -3.525 -0.435 0)
			(layer "F.SilkS")
			(effects
				(font
					(size 0.7 0.7)
					(thickness 0.15)
				)
				(justify right bottom)
			)
		)
		(property "Value" "C_10u_0402"
			(at 0 1.4 0)
			(layer "F.Fab")
			(effects
				(font
					(size 0.7 0.7)
					(thickness 0.15)
				)
				(justify right bottom)
			)
		)
		(property "Datasheet" "https://www.yageo.com/en/Chart/Download/pdf/CC0402MRX5R5BB106"
			(at 0 0 180)
			(layer "F.Fab")
			(hide yes)
			(effects
				(font
					(size 1.27 1.27)
					(thickness 0.15)
				)
			)
		)
		(property "Description" "SMD Multilayer Ceramic Capacitor, 10 µF, 6.3 V, 0402 [1005 Metric], ± 20%, X5R, CC Series"
			(at 0 0 180)
			(layer "F.Fab")
			(hide yes)
			(effects
				(font
					(size 1.27 1.27)
					(thickness 0.15)
				)
			)
		)
		(property "Author" "Antmicro"
			(at 171.75 141.33 0)
			(layer "F.Fab")
			(hide yes)
			(effects
				(font
					(size 1 1)
					(thickness 0.15)
				)
			)
		)
		(property "Dielectric" ""
			(at 171.75 141.33 0)
			(layer "F.Fab")
			(hide yes)
			(effects
				(font
					(size 1 1)
					(thickness 0.15)
				)
			)
		)
		(property "License" "Apache-2.0"
			(at 171.75 141.33 0)
			(layer "F.Fab")
			(hide yes)
			(effects
				(font
					(size 1 1)
					(thickness 0.15)
				)
			)
		)
		(property "MPN" "CC0402MRX5R5BB106"
			(at 171.75 141.33 0)
			(layer "F.Fab")
			(hide yes)
			(effects
				(font
					(size 1 1)
					(thickness 0.15)
				)
			)
		)
		(property "Manufacturer" "YAGEO"
			(at 171.75 141.33 0)
			(layer "F.Fab")
			(hide yes)
			(effects
				(font
					(size 1 1)
					(thickness 0.15)
				)
			)
		)
		(property "Val" "10u"
			(at 171.75 141.33 0)
			(layer "F.Fab")
			(hide yes)
			(effects
				(font
					(size 1 1)
					(thickness 0.15)
				)
			)
		)
		(property "Voltage" ""
			(at 171.75 141.33 0)
			(layer "F.Fab")
			(hide yes)
			(effects
				(font
					(size 1 1)
					(thickness 0.15)
				)
			)
		)
		(sheetname "/Power supply/")
		(sheetfile "power-supply.kicad_sch")
		(attr smd)
		(fp_rect
			(start -0.925 -0.47)
			(end 0.925 0.47)
			(stroke
				(width 0.05)
				(type default)
			)
			(fill no)
			(layer "F.CrtYd")
		)
		(fp_line
			(start 0.504 0.248)
			(end -0.494 0.248)
			(stroke
				(width 0.15)
				(type solid)
			)
			(layer "F.Fab")
		)
		(fp_line
			(start 0.504 -0.25)
			(end 0.504 0.248)
			(stroke
				(width 0.15)
				(type solid)
			)
			(layer "F.Fab")
		)
		(fp_line
			(start -0.494 0.248)
			(end -0.494 -0.25)
			(stroke
				(width 0.15)
				(type solid)
			)
			(layer "F.Fab")
		)
		(fp_line
			(start -0.494 -0.25)
			(end 0.504 -0.25)
			(stroke
				(width 0.15)
				(type solid)
			)
			(layer "F.Fab")
		)
		(pad "1" smd roundrect
			(at -0.48 0 180)
			(size 0.59 0.64)
			(layers "F.Cu" "F.Mask" "F.Paste")
			(roundrect_rratio 0.25)
			(net 1 "GND")
			(pintype "passive")
		)
		(pad "2" smd roundrect
			(at 0.48 0 180)
			(size 0.59 0.64)
			(layers "F.Cu" "F.Mask" "F.Paste")
			(roundrect_rratio 0.25)
			(net 60 "Net-(C101-Pad2)")
			(pintype "passive")
		)
	)
	(footprint "antmicro-footprints:SC70-3"
		(layer "F.Cu")
		(at 87.8 77.33 -90)
		(property "Reference" "Q6"
			(at -0.53 -5.55 90)
			(layer "F.SilkS")
			(effects
				(font
					(size 0.7 0.7)
					(thickness 0.15)
				)
				(justify right bottom)
			)
		)
		(property "Value" "BSS138PW"
			(at 0 2.3 90)
			(layer "F.Fab")
			(effects
				(font
					(size 0.7 0.7)
					(thickness 0.15)
				)
				(justify right bottom)
			)
		)
		(property "Datasheet" "https://assets.nexperia.com/documents/data-sheet/BSS138PW.pdf"
			(at 0 0 270)
			(layer "F.Fab")
			(hide yes)
			(effects
				(font
					(size 1.27 1.27)
					(thickness 0.15)
				)
			)
		)
		(property "Description" "Power MOSFET, N Channel, 60 V, 320 mA, 0.9 ohm, SOT-323, Surface Mount"
			(at 0 0 270)
			(layer "F.Fab")
			(hide yes)
			(effects
				(font
					(size 1.27 1.27)
					(thickness 0.15)
				)
			)
		)
		(property "Author" "Antmicro"
			(at 10.47 165.13 0)
			(layer "F.Fab")
			(hide yes)
			(effects
				(font
					(size 1 1)
					(thickness 0.15)
				)
			)
		)
		(property "License" "Apache-2.0"
			(at 10.47 165.13 0)
			(layer "F.Fab")
			(hide yes)
			(effects
				(font
					(size 1 1)
					(thickness 0.15)
				)
			)
		)
		(property "MPN" "BSS138PW"
			(at 10.47 165.13 0)
			(layer "F.Fab")
			(hide yes)
			(effects
				(font
					(size 1 1)
					(thickness 0.15)
				)
			)
		)
		(property "Manufacturer" "Nexperia"
			(at 10.47 165.13 0)
			(layer "F.Fab")
			(hide yes)
			(effects
				(font
					(size 1 1)
					(thickness 0.15)
				)
			)
		)
		(sheetname "/Power supply/")
		(sheetfile "power-supply.kicad_sch")
		(attr smd)
		(fp_line
			(start -0.3 1)
			(end 0.627 1.001)
			(stroke
				(width 0.15)
				(type solid)
			)
			(layer "F.SilkS")
		)
		(fp_line
			(start 0.627 0.6)
			(end 0.627 1.001)
			(stroke
				(width 0.15)
				(type solid)
			)
			(layer "F.SilkS")
		)
		(fp_line
			(start 0.627 -0.6)
			(end 0.627 -0.999)
			(stroke
				(width 0.15)
				(type solid)
			)
			(layer "F.SilkS")
		)
		(fp_line
			(start -0.3 -1)
			(end 0.627 -0.999)
			(stroke
				(width 0.15)
				(type solid)
			)
			(layer "F.SilkS")
		)
		(fp_line
			(start -0.9 1.3)
			(end -0.9 1)
			(stroke
				(width 0.05)
				(type solid)
			)
			(layer "F.CrtYd")
		)
		(fp_line
			(start 0.9 1.3)
			(end -0.9 1.3)
			(stroke
				(width 0.05)
				(type solid)
			)
			(layer "F.CrtYd")
		)
		(fp_line
			(start -1.4 1)
			(end -1.4 -1)
			(stroke
				(width 0.05)
				(type solid)
			)
			(layer "F.CrtYd")
		)
		(fp_line
			(start -0.9 1)
			(end -1.4 1)
			(stroke
				(width 0.05)
				(type solid)
			)
			(layer "F.CrtYd")
		)
		(fp_line
			(start 0.9 0.4)
			(end 0.9 1.3)
			(stroke
				(width 0.05)
				(type solid)
			)
			(layer "F.CrtYd")
		)
		(fp_line
			(start 1.4 0.4)
			(end 0.9 0.4)
			(stroke
				(width 0.05)
				(type solid)
			)
			(layer "F.CrtYd")
		)
		(fp_line
			(start 0.9 -0.4)
			(end 1.4 -0.4)
			(stroke
				(width 0.05)
				(type solid)
			)
			(layer "F.CrtYd")
		)
		(fp_line
			(start 1.4 -0.4)
			(end 1.4 0.4)
			(stroke
				(width 0.05)
				(type solid)
			)
			(layer "F.CrtYd")
		)
		(fp_line
			(start -0.9 -1)
			(end -1.4 -1)
			(stroke
				(width 0.05)
				(type solid)
			)
			(layer "F.CrtYd")
		)
		(fp_line
			(start -0.9 -1.3)
			(end -0.9 -1)
			(stroke
				(width 0.05)
				(type solid)
			)
			(layer "F.CrtYd")
		)
		(fp_line
			(start -0.9 -1.3)
			(end 0.9 -1.3)
			(stroke
				(width 0.05)
				(type solid)
			)
			(layer "F.CrtYd")
		)
		(fp_line
			(start 0.9 -1.3)
			(end 0.9 -0.4)
			(stroke
				(width 0.05)
				(type solid)
			)
			(layer "F.CrtYd")
		)
		(fp_rect
			(start -0.623 -0.999)
			(end 0.627 1.001)
			(stroke
				(width 0.15)
				(type solid)
			)
			(fill no)
			(layer "F.Fab")
		)
		(pad "1" smd rect
			(at -1.051 -0.65)
			(size 0.6 0.6)
			(layers "F.Cu" "F.Mask" "F.Paste")
			(net 534 "/Power supply/1V2_PG")
			(pinfunction "G")
			(pintype "input")
		)
		(pad "2" smd rect
			(at -1.051 0.65)
			(size 0.6 0.6)
			(layers "F.Cu" "F.Mask" "F.Paste")
			(net 1 "GND")
			(pinfunction "S")
			(pintype "passive")
		)
		(pad "3" smd rect
			(at 1.05 0)
			(size 0.6 0.6)
			(layers "F.Cu" "F.Mask" "F.Paste")
			(net 313 "Net-(D14-C)")
			(pinfunction "D")
			(pintype "passive")
		)
	)
	(footprint "antmicro-footprints:R_0402_1005Metric"
		(layer "F.Cu")
		(at 85.65 76.75)
		(descr "Resistor SMD 0402")
		(tags "resistor SMD 0402")
		(property "Reference" "R189"
			(at 3.75 0.945 0)
			(layer "F.SilkS")
			(effects
				(font
					(size 0.7 0.7)
					(thickness 0.15)
				)
				(justify left bottom)
			)
		)
		(property "Value" "R_10k_0402"
			(at 0 1.4 0)
			(layer "F.Fab")
			(effects
				(font
					(size 0.7 0.7)
					(thickness 0.15)
				)
				(justify left bottom)
			)
		)
		(property "Datasheet" "https://www.bourns.com/docs/product-datasheets/cr.pdf"
			(at 0 0 0)
			(layer "F.Fab")
			(hide yes)
			(effects
				(font
					(size 1.27 1.27)
					(thickness 0.15)
				)
			)
		)
		(property "Description" "SMD Chip Resistor, 10 kohm, ± 1%, 62.5 mW, 0402 [1005 Metric], Thick Film, General Purpose"
			(at 0 0 0)
			(layer "F.Fab")
			(hide yes)
			(effects
				(font
					(size 1.27 1.27)
					(thickness 0.15)
				)
			)
		)
		(property "Author" "Antmicro"
			(at 0 0 0)
			(layer "F.Fab")
			(hide yes)
			(effects
				(font
					(size 1 1)
					(thickness 0.15)
				)
			)
		)
		(property "License" "Apache-2.0"
			(at 0 0 0)
			(layer "F.Fab")
			(hide yes)
			(effects
				(font
					(size 1 1)
					(thickness 0.15)
				)
			)
		)
		(property "MPN" "CR0402-FX-1002GLF"
			(at 0 0 0)
			(layer "F.Fab")
			(hide yes)
			(effects
				(font
					(size 1 1)
					(thickness 0.15)
				)
			)
		)
		(property "Manufacturer" "Bourns"
			(at 0 0 0)
			(layer "F.Fab")
			(hide yes)
			(effects
				(font
					(size 1 1)
					(thickness 0.15)
				)
			)
		)
		(property "Tolerance" "1%"
			(at 0 0 0)
			(layer "F.Fab")
			(hide yes)
			(effects
				(font
					(size 1 1)
					(thickness 0.15)
				)
			)
		)
		(property "Val" "10k"
			(at 0 0 0)
			(layer "F.Fab")
			(hide yes)
			(effects
				(font
					(size 1 1)
					(thickness 0.15)
				)
			)
		)
		(sheetname "/Power supply/")
		(sheetfile "power-supply.kicad_sch")
		(attr smd)
		(fp_rect
			(start -0.925 -0.47)
			(end 0.925 0.47)
			(stroke
				(width 0.05)
				(type default)
			)
			(fill no)
			(layer "F.CrtYd")
		)
		(fp_rect
			(start -0.5 -0.25)
			(end 0.5 0.25)
			(stroke
				(width 0.15)
				(type solid)
			)
			(fill no)
			(layer "F.Fab")
		)
		(pad "1" smd roundrect
			(at -0.48 0)
			(size 0.59 0.64)
			(layers "F.Cu" "F.Mask" "F.Paste")
			(roundrect_rratio 0.25)
			(net 4 "VCC5V0")
			(pintype "passive")
		)
		(pad "2" smd roundrect
			(at 0.48 0)
			(size 0.59 0.64)
			(layers "F.Cu" "F.Mask" "F.Paste")
			(roundrect_rratio 0.25)
			(net 534 "/Power supply/1V2_PG")
			(pintype "passive")
		)
	)
)
